FILE_TYPE = MULTI_PHYS_TABLE;
PART 'SCONN80_E67482007'
{======================================================================================================================================================================================}
:PACK_TYPE | MATERIAL | PART_NUMBER     = EnvComp | PART_NUMBER  | JEDEC_TYPE          | CLASS | DESCRIPTION                     | HEIGHT     | COMPONENT_TYPE | LEAD_LENGTH | LPID   | SPEED_URL | Status |RPL| AML | Bus_Unit | Days ;
{======================================================================================================================================================================================}
'SM'       | 'CONN'   | 'E67482-007'(!) = ''      | 'E67482-007' | 'SCONN80_E67482007' | 'IO'  | 'CONN,BTB,80P,RCP,VT,0MM,.8MM'  | '0.472 IN' | 'SMTCONN'      | ''          | '1859' | 'http://speed.intel.com:8081/speed/module/pdm/item/pdm_item_detail_direct.asp?item_cde=E67482-007&item_rev=01&url_param=unused' | '' | '' | '' | '' | '' 
'SM'       | 'EMPTY'  | 'E67482-007'(!) = ''      | 'E67482-007' | 'SCONN80_E67482007' | 'IO'  | 'CONN,BTB,80P,RCP,VT,0MM,.8MM'  | '0.472 IN' | 'SMTCONN'      | ''          | '1859' | 'http://speed.intel.com:8081/speed/module/pdm/item/pdm_item_detail_direct.asp?item_cde=E67482-007&item_rev=01&url_param=unused' | '' | '' | '' | '' | '' 
END_PART
END.
